(kicad_pcb
	(version 20260206)
	(generator "pcbnew")
	(generator_version "10.0")
	(general
		(thickness 1.6)
		(legacy_teardrops no)
	)
	(paper "A4")
	(title_block
		(title "01162023_DA0F0TEBIF0_F0T_Expander_BD_F_brd_V02_OCP.brd")
		(comment 1 "Grand Teton / footprints 5185-5191 of 9728")
	)
	(layers
		(0 "F.Cu" signal "TOP")
		(4 "In1.Cu" signal "GND")
		(6 "In2.Cu" signal "VCC")
		(8 "In3.Cu" signal "VCC1")
		(10 "In4.Cu" signal "GND1")
		(12 "In5.Cu" signal "IN1")
		(14 "In6.Cu" signal "GND2")
		(16 "In7.Cu" signal "IN2")
		(18 "In8.Cu" signal "GND3")
		(20 "In9.Cu" signal "IN3")
		(22 "In10.Cu" signal "GND4")
		(24 "In11.Cu" signal "IN4")
		(26 "In12.Cu" signal "GND5")
		(28 "In13.Cu" signal "IN5")
		(30 "In14.Cu" signal "GND6")
		(32 "In15.Cu" signal "IN6")
		(34 "In16.Cu" signal "GND7")
		(2 "B.Cu" signal "BOTTOM")
		(9 "F.Adhes" user "F.Adhesive")
		(11 "B.Adhes" user "B.Adhesive")
		(13 "F.Paste" user "Package Geometry/Pastemask Top")
		(15 "B.Paste" user "Package Geometry/Pastemask Bottom")
		(5 "F.SilkS" user "Ref Des/Silkscreen Top")
		(7 "B.SilkS" user "Ref Des/Silkscreen Bottom")
		(1 "F.Mask" user "Board Geometry/Soldermask Top")
		(3 "B.Mask" user "Board Geometry/Soldermask Bottom")
		(17 "Dwgs.User" user "User.Drawings")
		(19 "Cmts.User" user "User.Comments")
		(21 "Eco1.User" user "User.Eco1")
		(23 "Eco2.User" user "User.Eco2")
		(25 "Edge.Cuts" user "Board Geometry/Outline")
		(27 "Margin" user)
		(31 "F.CrtYd" user "Package Geometry/Place Bound Top")
		(29 "B.CrtYd" user "Package Geometry/Place Bound Bottom")
		(35 "F.Fab" user "Ref Des/Assembly Top")
		(33 "B.Fab" user "Ref Des/Assembly Bottom")
	)
	(footprint ""
		(layer "F.Cu")
		(at 349.123 -234.061 -90)
		(property "Reference" "R3583"
			(at 0 0 270)
			(layer "F.SilkS")
			(hide yes)
			(effects
				(font
					(size 1.27 1.27)
				)
			)
		)
		(property "Value" ""
			(at 0 0 270)
			(layer "F.Fab")
			(effects
				(font
					(size 1.27 1.27)
				)
			)
		)
		(duplicate_pad_numbers_are_jumpers no)
		(fp_line
			(start -0.7874 0.4064)
			(end -0.7874 -0.4064)
			(stroke
				(width 0.1524)
				(type default)
			)
			(layer "F.SilkS")
		)
		(fp_line
			(start 0.7874 0.4064)
			(end -0.7874 0.4064)
			(stroke
				(width 0.1524)
				(type default)
			)
			(layer "F.SilkS")
		)
		(fp_line
			(start -0.7874 -0.4064)
			(end 0.7874 -0.4064)
			(stroke
				(width 0.1524)
				(type default)
			)
			(layer "F.SilkS")
		)
		(fp_line
			(start 0.7874 -0.4064)
			(end 0.7874 0.4064)
			(stroke
				(width 0.1524)
				(type default)
			)
			(layer "F.SilkS")
		)
		(fp_line
			(start -0.67945 0.3048)
			(end -0.67945 -0.305054)
			(stroke
				(width 0.1)
				(type default)
			)
			(layer "F.Fab")
		)
		(fp_line
			(start -0.12065 0.3048)
			(end -0.67945 0.3048)
			(stroke
				(width 0.1)
				(type default)
			)
			(layer "F.Fab")
		)
		(fp_line
			(start 0.120396 0.3048)
			(end 0.120396 0.2794)
			(stroke
				(width 0.1)
				(type default)
			)
			(layer "F.Fab")
		)
		(fp_line
			(start 0.67945 0.3048)
			(end 0.120396 0.3048)
			(stroke
				(width 0.1)
				(type default)
			)
			(layer "F.Fab")
		)
		(fp_line
			(start -0.12065 0.2794)
			(end -0.12065 0.3048)
			(stroke
				(width 0.1)
				(type default)
			)
			(layer "F.Fab")
		)
		(fp_line
			(start 0.120396 0.2794)
			(end -0.12065 0.2794)
			(stroke
				(width 0.1)
				(type default)
			)
			(layer "F.Fab")
		)
		(fp_line
			(start -0.12065 -0.2794)
			(end 0.12065 -0.2794)
			(stroke
				(width 0.1)
				(type default)
			)
			(layer "F.Fab")
		)
		(fp_line
			(start 0.12065 -0.2794)
			(end 0.12065 -0.3048)
			(stroke
				(width 0.1)
				(type default)
			)
			(layer "F.Fab")
		)
		(fp_line
			(start 0.12065 -0.3048)
			(end 0.67945 -0.3048)
			(stroke
				(width 0.1)
				(type default)
			)
			(layer "F.Fab")
		)
		(fp_line
			(start 0.67945 -0.3048)
			(end 0.67945 0.3048)
			(stroke
				(width 0.1)
				(type default)
			)
			(layer "F.Fab")
		)
		(fp_line
			(start -0.67945 -0.305054)
			(end -0.12065 -0.305054)
			(stroke
				(width 0.1)
				(type default)
			)
			(layer "F.Fab")
		)
		(fp_line
			(start -0.12065 -0.305054)
			(end -0.12065 -0.2794)
			(stroke
				(width 0.1)
				(type default)
			)
			(layer "F.Fab")
		)
		(pad "1" smd circle
			(at -0.40005 0 270)
			(size 0 0)
			(layers "F.Cu" "F.Mask" "F.Paste")
			(net "SSD6_CLK_EN_R_N")
		)
		(pad "2" smd circle
			(at 0.40005 0 270)
			(size 0 0)
			(layers "F.Cu" "F.Mask" "F.Paste")
			(net "SSD6_CLK_EN_N")
		)
	)
	(footprint ""
		(layer "F.Cu")
		(at 26.243788 -47.92091)
		(property "Reference" "R504"
			(at 0 0 0)
			(layer "F.SilkS")
			(hide yes)
			(effects
				(font
					(size 1.27 1.27)
				)
			)
		)
		(property "Value" ""
			(at 0 0 0)
			(layer "F.Fab")
			(effects
				(font
					(size 1.27 1.27)
				)
			)
		)
		(duplicate_pad_numbers_are_jumpers no)
		(fp_line
			(start -0.7874 -0.4064)
			(end 0.7874 -0.4064)
			(stroke
				(width 0.1524)
				(type default)
			)
			(layer "F.SilkS")
		)
		(fp_line
			(start -0.7874 0.4064)
			(end -0.7874 -0.4064)
			(stroke
				(width 0.1524)
				(type default)
			)
			(layer "F.SilkS")
		)
		(fp_line
			(start 0.7874 -0.4064)
			(end 0.7874 0.4064)
			(stroke
				(width 0.1524)
				(type default)
			)
			(layer "F.SilkS")
		)
		(fp_line
			(start 0.7874 0.4064)
			(end -0.7874 0.4064)
			(stroke
				(width 0.1524)
				(type default)
			)
			(layer "F.SilkS")
		)
		(fp_line
			(start -0.67945 -0.305054)
			(end -0.12065 -0.305054)
			(stroke
				(width 0.1)
				(type default)
			)
			(layer "F.Fab")
		)
		(fp_line
			(start -0.67945 0.3048)
			(end -0.67945 -0.305054)
			(stroke
				(width 0.1)
				(type default)
			)
			(layer "F.Fab")
		)
		(fp_line
			(start -0.12065 -0.305054)
			(end -0.12065 -0.2794)
			(stroke
				(width 0.1)
				(type default)
			)
			(layer "F.Fab")
		)
		(fp_line
			(start -0.12065 -0.2794)
			(end 0.12065 -0.2794)
			(stroke
				(width 0.1)
				(type default)
			)
			(layer "F.Fab")
		)
		(fp_line
			(start -0.12065 0.2794)
			(end -0.12065 0.3048)
			(stroke
				(width 0.1)
				(type default)
			)
			(layer "F.Fab")
		)
		(fp_line
			(start -0.12065 0.3048)
			(end -0.67945 0.3048)
			(stroke
				(width 0.1)
				(type default)
			)
			(layer "F.Fab")
		)
		(fp_line
			(start 0.120396 0.2794)
			(end -0.12065 0.2794)
			(stroke
				(width 0.1)
				(type default)
			)
			(layer "F.Fab")
		)
		(fp_line
			(start 0.120396 0.3048)
			(end 0.120396 0.2794)
			(stroke
				(width 0.1)
				(type default)
			)
			(layer "F.Fab")
		)
		(fp_line
			(start 0.12065 -0.3048)
			(end 0.67945 -0.3048)
			(stroke
				(width 0.1)
				(type default)
			)
			(layer "F.Fab")
		)
		(fp_line
			(start 0.12065 -0.2794)
			(end 0.12065 -0.3048)
			(stroke
				(width 0.1)
				(type default)
			)
			(layer "F.Fab")
		)
		(fp_line
			(start 0.67945 -0.3048)
			(end 0.67945 0.3048)
			(stroke
				(width 0.1)
				(type default)
			)
			(layer "F.Fab")
		)
		(fp_line
			(start 0.67945 0.3048)
			(end 0.120396 0.3048)
			(stroke
				(width 0.1)
				(type default)
			)
			(layer "F.Fab")
		)
		(pad "1" smd circle
			(at -0.40005 0)
			(size 0 0)
			(layers "F.Cu" "F.Mask" "F.Paste")
			(net "P3V3_AUX")
		)
		(pad "2" smd circle
			(at 0.40005 0)
			(size 0 0)
			(layers "F.Cu" "F.Mask" "F.Paste")
			(net "SSD_0_7_ADC_ALERT_N")
		)
	)
	(footprint ""
		(layer "F.Cu")
		(at 369.495578 -83.784694 180)
		(property "Reference" "R1604"
			(at 0 0 180)
			(layer "F.SilkS")
			(hide yes)
			(effects
				(font
					(size 1.27 1.27)
				)
			)
		)
		(property "Value" ""
			(at 0 0 180)
			(layer "F.Fab")
			(effects
				(font
					(size 1.27 1.27)
				)
			)
		)
		(duplicate_pad_numbers_are_jumpers no)
		(fp_line
			(start 0.7874 0.4064)
			(end -0.7874 0.4064)
			(stroke
				(width 0.1524)
				(type default)
			)
			(layer "F.SilkS")
		)
		(fp_line
			(start 0.7874 -0.4064)
			(end 0.7874 0.4064)
			(stroke
				(width 0.1524)
				(type default)
			)
			(layer "F.SilkS")
		)
		(fp_line
			(start -0.7874 0.4064)
			(end -0.7874 -0.4064)
			(stroke
				(width 0.1524)
				(type default)
			)
			(layer "F.SilkS")
		)
		(fp_line
			(start -0.7874 -0.4064)
			(end 0.7874 -0.4064)
			(stroke
				(width 0.1524)
				(type default)
			)
			(layer "F.SilkS")
		)
		(fp_line
			(start 0.67945 0.3048)
			(end 0.120396 0.3048)
			(stroke
				(width 0.1)
				(type default)
			)
			(layer "F.Fab")
		)
		(fp_line
			(start 0.67945 -0.3048)
			(end 0.67945 0.3048)
			(stroke
				(width 0.1)
				(type default)
			)
			(layer "F.Fab")
		)
		(fp_line
			(start 0.12065 -0.2794)
			(end 0.12065 -0.3048)
			(stroke
				(width 0.1)
				(type default)
			)
			(layer "F.Fab")
		)
		(fp_line
			(start 0.12065 -0.3048)
			(end 0.67945 -0.3048)
			(stroke
				(width 0.1)
				(type default)
			)
			(layer "F.Fab")
		)
		(fp_line
			(start 0.120396 0.3048)
			(end 0.120396 0.2794)
			(stroke
				(width 0.1)
				(type default)
			)
			(layer "F.Fab")
		)
		(fp_line
			(start 0.120396 0.2794)
			(end -0.12065 0.2794)
			(stroke
				(width 0.1)
				(type default)
			)
			(layer "F.Fab")
		)
		(fp_line
			(start -0.12065 0.3048)
			(end -0.67945 0.3048)
			(stroke
				(width 0.1)
				(type default)
			)
			(layer "F.Fab")
		)
		(fp_line
			(start -0.12065 0.2794)
			(end -0.12065 0.3048)
			(stroke
				(width 0.1)
				(type default)
			)
			(layer "F.Fab")
		)
		(fp_line
			(start -0.12065 -0.2794)
			(end 0.12065 -0.2794)
			(stroke
				(width 0.1)
				(type default)
			)
			(layer "F.Fab")
		)
		(fp_line
			(start -0.12065 -0.305054)
			(end -0.12065 -0.2794)
			(stroke
				(width 0.1)
				(type default)
			)
			(layer "F.Fab")
		)
		(fp_line
			(start -0.67945 0.3048)
			(end -0.67945 -0.305054)
			(stroke
				(width 0.1)
				(type default)
			)
			(layer "F.Fab")
		)
		(fp_line
			(start -0.67945 -0.305054)
			(end -0.12065 -0.305054)
			(stroke
				(width 0.1)
				(type default)
			)
			(layer "F.Fab")
		)
		(pad "1" smd circle
			(at -0.40005 0 180)
			(size 0 0)
			(layers "F.Cu" "F.Mask" "F.Paste")
			(net "P3V3_AUX")
		)
		(pad "2" smd circle
			(at 0.40005 0 180)
			(size 0 0)
			(layers "F.Cu" "F.Mask" "F.Paste")
			(net "SMB_BIC_I2C9_MUX1_SSD13_R_SDA")
		)
	)
	(footprint ""
		(layer "F.Cu")
		(at 320.354452 -222.119698 180)
		(property "Reference" "D16"
			(at 3.743452 0.103632 0)
			(unlocked yes)
			(layer "F.SilkS")
			(effects
				(font
					(size 0.7874 0.5842)
					(thickness 0.1524)
				)
				(justify left)
			)
		)
		(property "Value" ""
			(at 0 0 180)
			(layer "F.Fab")
			(effects
				(font
					(size 1.27 1.27)
				)
			)
		)
		(duplicate_pad_numbers_are_jumpers no)
		(fp_line
			(start 1.16078 0.4826)
			(end -0.64008 0.4826)
			(stroke
				(width 0.1524)
				(type default)
			)
			(layer "F.SilkS")
		)
		(fp_line
			(start 1.16078 -0.4826)
			(end 1.16078 0.4826)
			(stroke
				(width 0.1524)
				(type default)
			)
			(layer "F.SilkS")
		)
		(fp_line
			(start 1.03378 0.4826)
			(end -0.79248 0.4826)
			(stroke
				(width 0.1524)
				(type default)
			)
			(layer "F.SilkS")
		)
		(fp_line
			(start 1.03378 -0.4826)
			(end 1.03378 0.4826)
			(stroke
				(width 0.1524)
				(type default)
			)
			(layer "F.SilkS")
		)
		(fp_line
			(start 0.90678 0.4826)
			(end -0.90678 0.4826)
			(stroke
				(width 0.1524)
				(type default)
			)
			(layer "F.SilkS")
		)
		(fp_line
			(start 0.90678 -0.4826)
			(end 0.90678 0.4826)
			(stroke
				(width 0.1524)
				(type default)
			)
			(layer "F.SilkS")
		)
		(fp_line
			(start -0.64008 -0.4826)
			(end 1.16078 -0.4826)
			(stroke
				(width 0.1524)
				(type default)
			)
			(layer "F.SilkS")
		)
		(fp_line
			(start -0.79248 -0.4826)
			(end 1.03378 -0.4826)
			(stroke
				(width 0.1524)
				(type default)
			)
			(layer "F.SilkS")
		)
		(fp_line
			(start -0.89408 -0.4826)
			(end 0.90678 -0.4826)
			(stroke
				(width 0.1524)
				(type default)
			)
			(layer "F.SilkS")
		)
		(fp_line
			(start -0.90678 0.4826)
			(end -0.90678 -0.4699)
			(stroke
				(width 0.1524)
				(type default)
			)
			(layer "F.SilkS")
		)
		(fp_line
			(start 0.499872 0.249936)
			(end -0.499872 0.249936)
			(stroke
				(width 0.1)
				(type default)
			)
			(layer "F.Fab")
		)
		(fp_line
			(start 0.499872 -0.249936)
			(end 0.499872 0.249936)
			(stroke
				(width 0.1)
				(type default)
			)
			(layer "F.Fab")
		)
		(fp_line
			(start -0.499872 0.249936)
			(end -0.499872 -0.249936)
			(stroke
				(width 0.1)
				(type default)
			)
			(layer "F.Fab")
		)
		(fp_line
			(start -0.499872 -0.249936)
			(end 0.499872 -0.249936)
			(stroke
				(width 0.1)
				(type default)
			)
			(layer "F.Fab")
		)
		(pad "A" smd rect
			(at -0.47498 0 180)
			(size 0.6096 0.7112)
			(layers "F.Cu" "F.Mask" "F.Paste")
			(net "LED_POSTCODE_R_3")
		)
		(pad "C" smd rect
			(at 0.47498 0 180)
			(size 0.6096 0.7112)
			(layers "F.Cu" "F.Mask" "F.Paste")
			(net "FPGA_DEBUG_LED_R_N")
		)
	)
	(footprint ""
		(layer "F.Cu")
		(at 276.838664 -22.867366 90)
		(property "Reference" "C3941"
			(at 0 0 90)
			(layer "F.SilkS")
			(hide yes)
			(effects
				(font
					(size 1.27 1.27)
				)
			)
		)
		(property "Value" ""
			(at 0 0 90)
			(layer "F.Fab")
			(effects
				(font
					(size 1.27 1.27)
				)
			)
		)
		(duplicate_pad_numbers_are_jumpers no)
		(fp_line
			(start 0.7874 -0.4064)
			(end 0.7874 0.4064)
			(stroke
				(width 0.1524)
				(type default)
			)
			(layer "F.SilkS")
		)
		(fp_line
			(start -0.7874 -0.4064)
			(end 0.7874 -0.4064)
			(stroke
				(width 0.1524)
				(type default)
			)
			(layer "F.SilkS")
		)
		(fp_line
			(start 0.7874 0.4064)
			(end -0.7874 0.4064)
			(stroke
				(width 0.1524)
				(type default)
			)
			(layer "F.SilkS")
		)
		(fp_line
			(start -0.7874 0.4064)
			(end -0.7874 -0.4064)
			(stroke
				(width 0.1524)
				(type default)
			)
			(layer "F.SilkS")
		)
		(fp_line
			(start -0.12065 -0.305054)
			(end -0.12065 -0.2794)
			(stroke
				(width 0.1)
				(type default)
			)
			(layer "F.Fab")
		)
		(fp_line
			(start -0.67945 -0.305054)
			(end -0.12065 -0.305054)
			(stroke
				(width 0.1)
				(type default)
			)
			(layer "F.Fab")
		)
		(fp_line
			(start 0.67945 -0.3048)
			(end 0.67945 0.3048)
			(stroke
				(width 0.1)
				(type default)
			)
			(layer "F.Fab")
		)
		(fp_line
			(start 0.12065 -0.3048)
			(end 0.67945 -0.3048)
			(stroke
				(width 0.1)
				(type default)
			)
			(layer "F.Fab")
		)
		(fp_line
			(start 0.12065 -0.2794)
			(end 0.12065 -0.3048)
			(stroke
				(width 0.1)
				(type default)
			)
			(layer "F.Fab")
		)
		(fp_line
			(start -0.12065 -0.2794)
			(end 0.12065 -0.2794)
			(stroke
				(width 0.1)
				(type default)
			)
			(layer "F.Fab")
		)
		(fp_line
			(start 0.120396 0.2794)
			(end -0.12065 0.2794)
			(stroke
				(width 0.1)
				(type default)
			)
			(layer "F.Fab")
		)
		(fp_line
			(start -0.12065 0.2794)
			(end -0.12065 0.3048)
			(stroke
				(width 0.1)
				(type default)
			)
			(layer "F.Fab")
		)
		(fp_line
			(start 0.67945 0.3048)
			(end 0.120396 0.3048)
			(stroke
				(width 0.1)
				(type default)
			)
			(layer "F.Fab")
		)
		(fp_line
			(start 0.120396 0.3048)
			(end 0.120396 0.2794)
			(stroke
				(width 0.1)
				(type default)
			)
			(layer "F.Fab")
		)
		(fp_line
			(start -0.12065 0.3048)
			(end -0.67945 0.3048)
			(stroke
				(width 0.1)
				(type default)
			)
			(layer "F.Fab")
		)
		(fp_line
			(start -0.67945 0.3048)
			(end -0.67945 -0.305054)
			(stroke
				(width 0.1)
				(type default)
			)
			(layer "F.Fab")
		)
		(pad "1" smd circle
			(at -0.40005 0 90)
			(size 0 0)
			(layers "F.Cu" "F.Mask" "F.Paste")
			(net "P12V_SSD9")
		)
		(pad "2" smd circle
			(at 0.40005 0 90)
			(size 0 0)
			(layers "F.Cu" "F.Mask" "F.Paste")
			(net "GND")
		)
	)
	(footprint ""
		(layer "F.Cu")
		(at 443.802262 -443.028832 90)
		(property "Reference" "J48"
			(at -3.5052 -5.552948 90)
			(unlocked yes)
			(layer "F.SilkS")
			(effects
				(font
					(size 0.7874 0.5842)
					(thickness 0.1524)
				)
				(justify left)
			)
		)
		(property "Value" ""
			(at 0 0 90)
			(layer "F.Fab")
			(effects
				(font
					(size 1.27 1.27)
				)
			)
		)
		(duplicate_pad_numbers_are_jumpers no)
		(fp_line
			(start 3.330702 -4.771136)
			(end 0 4.011168)
			(stroke
				(width 0.1524)
				(type default)
			)
			(layer "F.SilkS")
		)
		(fp_line
			(start -3.330702 -4.771136)
			(end 3.330702 -4.771136)
			(stroke
				(width 0.1524)
				(type default)
			)
			(layer "F.SilkS")
		)
		(fp_line
			(start 0 4.011168)
			(end -3.330702 -4.771136)
			(stroke
				(width 0.1524)
				(type default)
			)
			(layer "F.SilkS")
		)
		(fp_line
			(start 3.330702 -4.771136)
			(end 0 4.011168)
			(stroke
				(width 0.1)
				(type default)
			)
			(layer "F.Fab")
		)
		(fp_line
			(start -3.330702 -4.771136)
			(end 3.330702 -4.771136)
			(stroke
				(width 0.1)
				(type default)
			)
			(layer "F.Fab")
		)
		(fp_line
			(start 0 4.011168)
			(end -3.330702 -4.771136)
			(stroke
				(width 0.1)
				(type default)
			)
			(layer "F.Fab")
		)
		(pad "1" thru_hole circle
			(at 0 0 90)
			(size 2.159 2.159)
			(drill 1.7018)
			(layers "*.Cu" "*.Mask")
			(remove_unused_layers no)
			(net "COUPON_GND1")
			(clearance 0.0254)
			(thermal_gap 0.0254)
		)
		(pad "2" thru_hole circle
			(at -1.27 -3.348736 90)
			(size 2.159 2.159)
			(drill 1.7018)
			(layers "*.Cu" "*.Mask")
			(remove_unused_layers no)
			(net "TDR_SE_50_OHM_IN2")
			(clearance 0.0254)
			(thermal_gap 0.0254)
		)
		(pad "3" thru_hole circle
			(at 1.27 -3.348736 90)
			(size 2.159 2.159)
			(drill 1.7018)
			(layers "*.Cu" "*.Mask")
			(remove_unused_layers no)
			(net "TDR_SE_50_OHM_IN2")
			(clearance 0.0254)
			(thermal_gap 0.0254)
		)
	)
	(footprint ""
		(layer "F.Cu")
		(at 19.225768 -159.082994 -90)
		(property "Reference" "PD76"
			(at 3.838194 -2.771902 90)
			(unlocked yes)
			(layer "F.SilkS")
			(effects
				(font
					(size 0.7874 0.5842)
					(thickness 0.1524)
				)
				(justify left)
			)
		)
		(property "Value" ""
			(at 0 0 270)
			(layer "F.Fab")
			(effects
				(font
					(size 1.27 1.27)
				)
			)
		)
		(duplicate_pad_numbers_are_jumpers no)
		(fp_line
			(start -3.656584 1.970024)
			(end 4.240784 1.970024)
			(stroke
				(width 0.1524)
				(type default)
			)
			(layer "F.SilkS")
		)
		(fp_line
			(start 4.240784 1.970024)
			(end 4.240784 -1.970024)
			(stroke
				(width 0.1524)
				(type default)
			)
			(layer "F.SilkS")
		)
		(fp_line
			(start -3.656584 -1.970024)
			(end -3.656584 1.970024)
			(stroke
				(width 0.1524)
				(type default)
			)
			(layer "F.SilkS")
		)
		(fp_line
			(start 4.240784 -1.970024)
			(end -3.656584 -1.970024)
			(stroke
				(width 0.1524)
				(type default)
			)
			(layer "F.SilkS")
		)
		(fp_poly
			(pts
				(xy 3.580384 1.970024) (xy 3.580384 -1.970024) (xy 4.240784 -1.970024) (xy 4.240784 1.970024)
			)
			(stroke
				(width 0)
				(type default)
			)
			(fill yes)
			(layer "F.SilkS")
		)
		(fp_line
			(start -2.3749 1.970024)
			(end 2.3749 1.970024)
			(stroke
				(width 0.1)
				(type default)
			)
			(layer "F.Fab")
		)
		(fp_line
			(start 2.3749 1.970024)
			(end 2.3749 -1.970024)
			(stroke
				(width 0.1)
				(type default)
			)
			(layer "F.Fab")
		)
		(fp_line
			(start -2.3749 -1.970024)
			(end -2.3749 1.970024)
			(stroke
				(width 0.1)
				(type default)
			)
			(layer "F.Fab")
		)
		(fp_line
			(start 2.3749 -1.970024)
			(end -2.3749 -1.970024)
			(stroke
				(width 0.1)
				(type default)
			)
			(layer "F.Fab")
		)
		(fp_text user "+"
			(at -4.9784 -0.23495 270)
			(unlocked yes)
			(layer "F.Fab")
			(effects
				(font
					(size 1.905 1.4224)
					(thickness 0.1524)
				)
				(justify left)
			)
		)
		(fp_text user "-"
			(at 4.1656 -0.23495 270)
			(unlocked yes)
			(layer "F.Fab")
			(effects
				(font
					(size 1.905 1.4224)
					(thickness 0.1524)
				)
				(justify left)
			)
		)
		(pad "A" smd rect
			(at -2.450084 0 270)
			(size 2.159 2.2606)
			(layers "F.Cu" "F.Mask" "F.Paste")
			(net "GND")
		)
		(pad "C" smd rect
			(at 2.450084 0 270)
			(size 2.159 2.2606)
			(layers "F.Cu" "F.Mask" "F.Paste")
			(net "P12V_AUX")
		)
	)
)
